# carac PCB discovery v1 revB.xlsx — Feuil1 (pcb-characteristics)
| Layers | 2 |
| Class | 4 |
| Board thickness | 2,5mm |
| Material | FR4 |
| Finish | NiAu |
| Vernis épargne | yes |
| Serigraphy | yes |
| Width | 150mm |
| Length | 100mm |
